(kicad_pcb
	(version 20260206)
	(generator "pcbnew")
	(generator_version "10.0")
	(general
		(thickness 1.6)
		(legacy_teardrops no)
	)
	(paper "A4")
	(title_block
		(title "Bryce Canyon_F.DPB_16315-1-OCP.brd")
		(comment 1 "Bryce Canyon / footprints 1778-1784 of 2223")
	)
	(layers
		(0 "F.Cu" signal "TOP")
		(4 "In1.Cu" signal "L2GND")
		(6 "In2.Cu" signal "L3")
		(8 "In3.Cu" signal "L4GND")
		(10 "In4.Cu" signal "L5")
		(12 "In5.Cu" signal "L6VCC")
		(14 "In6.Cu" signal "L7VCC")
		(16 "In7.Cu" signal "L8")
		(18 "In8.Cu" signal "L9GND")
		(20 "In9.Cu" signal "L10")
		(22 "In10.Cu" signal "L11GND")
		(2 "B.Cu" signal "BOTTOM")
		(9 "F.Adhes" user "F.Adhesive")
		(11 "B.Adhes" user "B.Adhesive")
		(13 "F.Paste" user "Package Geometry/Pastemask Top")
		(15 "B.Paste" user "Package Geometry/Pastemask Bottom")
		(5 "F.SilkS" user "Ref Des/Silkscreen Top")
		(7 "B.SilkS" user "Ref Des/Silkscreen Bottom")
		(1 "F.Mask" user "Board Geometry/Soldermask Top")
		(3 "B.Mask" user "Board Geometry/Soldermask Bottom")
		(17 "Dwgs.User" user "User.Drawings")
		(19 "Cmts.User" user "User.Comments")
		(21 "Eco1.User" user "User.Eco1")
		(23 "Eco2.User" user "User.Eco2")
		(25 "Edge.Cuts" user "Board Geometry/Outline")
		(27 "Margin" user)
		(31 "F.CrtYd" user "Package Geometry/Place Bound Top")
		(29 "B.CrtYd" user "Package Geometry/Place Bound Bottom")
		(35 "F.Fab" user "Ref Des/Assembly Top")
		(33 "B.Fab" user "Ref Des/Assembly Bottom")
	)
	(footprint ""
		(layer "F.Cu")
		(at 369.624102 -279.443942 90)
		(property "Reference" "R307"
			(at 0 0 90)
			(layer "F.SilkS")
			(hide yes)
			(effects
				(font
					(size 1.27 1.27)
				)
			)
		)
		(property "Value" "200KR2F-L-GP"
			(at 0.064008 -3.993896 90)
			(unlocked yes)
			(layer "F.Fab")
			(hide yes)
			(effects
				(font
					(size 1.016 1.016)
					(thickness 0.1524)
				)
			)
		)
		(property "Device Type" "R402H16"
			(at 0.064008 -5.517896 90)
			(unlocked yes)
			(layer "F.Fab")
			(hide yes)
			(effects
				(font
					(size 1.016 1.016)
					(thickness 0.1524)
				)
			)
		)
		(duplicate_pad_numbers_are_jumpers no)
		(fp_line
			(start 0.508 -0.9398)
			(end -0.508 -0.9398)
			(stroke
				(width 0.1524)
				(type default)
			)
			(layer "F.SilkS")
		)
		(fp_line
			(start -0.508 -0.9398)
			(end -0.508 0.9398)
			(stroke
				(width 0.1524)
				(type default)
			)
			(layer "F.SilkS")
		)
		(fp_rect
			(start -0.508 0.9398)
			(end 0.508 -0.9398)
			(stroke
				(width 0)
				(type default)
			)
			(fill no)
			(layer "F.CrtYd")
		)
		(fp_rect
			(start -0.508 0.9398)
			(end 0.508 -0.9398)
			(stroke
				(width 0)
				(type default)
			)
			(fill no)
			(layer "F.Fab")
		)
		(pad "1" smd custom
			(at 0 -0.4445 90)
			(size 0.1397 0.1397)
			(layers "F.Cu" "F.Mask" "F.Paste")
			(net "SW_HDD_R7")
			(options
				(clearance outline)
				(anchor circle)
			)
			(primitives
				(gr_poly
					(pts
						(arc
							(start -0.1778 -0.2794)
							(mid -0.249642 -0.249642)
							(end -0.2794 -0.1778)
						)
						(arc
							(start -0.2794 0.1778)
							(mid -0.249642 0.249642)
							(end -0.1778 0.2794)
						)
						(arc
							(start 0.1778 0.2794)
							(mid 0.249642 0.249642)
							(end 0.2794 0.1778)
						)
						(arc
							(start 0.2794 -0.1778)
							(mid 0.249642 -0.249642)
							(end 0.1778 -0.2794)
						)
					)
					(width 0)
					(fill yes)
				)
			)
		)
		(pad "2" smd custom
			(at 0 0.4445 90)
			(size 0.1397 0.1397)
			(layers "F.Cu" "F.Mask" "F.Paste")
			(net "SW_HDD_N7")
			(options
				(clearance outline)
				(anchor circle)
			)
			(primitives
				(gr_poly
					(pts
						(arc
							(start -0.1778 -0.2794)
							(mid -0.249642 -0.249642)
							(end -0.2794 -0.1778)
						)
						(arc
							(start -0.2794 0.1778)
							(mid -0.249642 0.249642)
							(end -0.1778 0.2794)
						)
						(arc
							(start 0.1778 0.2794)
							(mid 0.249642 0.249642)
							(end 0.2794 0.1778)
						)
						(arc
							(start 0.2794 -0.1778)
							(mid 0.249642 -0.249642)
							(end 0.1778 -0.2794)
						)
					)
					(width 0)
					(fill yes)
				)
			)
		)
	)
	(footprint ""
		(layer "F.Cu")
		(at 270.409416 -20.18411 -90)
		(property "Reference" "R1130"
			(at 0 0 270)
			(layer "F.SilkS")
			(hide yes)
			(effects
				(font
					(size 1.27 1.27)
				)
			)
		)
		(property "Value" "100KR2F-L1-GP"
			(at 0.064008 -3.993896 270)
			(unlocked yes)
			(layer "F.Fab")
			(hide yes)
			(effects
				(font
					(size 1.016 1.016)
					(thickness 0.1524)
				)
			)
		)
		(property "Device Type" "R402H16"
			(at 0.064008 -5.517896 270)
			(unlocked yes)
			(layer "F.Fab")
			(hide yes)
			(effects
				(font
					(size 1.016 1.016)
					(thickness 0.1524)
				)
			)
		)
		(duplicate_pad_numbers_are_jumpers no)
		(fp_line
			(start -0.508 -0.9398)
			(end -0.508 0.9398)
			(stroke
				(width 0.1524)
				(type default)
			)
			(layer "F.SilkS")
		)
		(fp_line
			(start 0.508 -0.9398)
			(end -0.508 -0.9398)
			(stroke
				(width 0.1524)
				(type default)
			)
			(layer "F.SilkS")
		)
		(fp_rect
			(start -0.508 0.9398)
			(end 0.508 -0.9398)
			(stroke
				(width 0)
				(type default)
			)
			(fill no)
			(layer "F.CrtYd")
		)
		(fp_rect
			(start -0.508 0.9398)
			(end 0.508 -0.9398)
			(stroke
				(width 0)
				(type default)
			)
			(fill no)
			(layer "F.Fab")
		)
		(pad "1" smd custom
			(at 0 -0.4445 270)
			(size 0.1397 0.1397)
			(layers "F.Cu" "F.Mask" "F.Paste")
			(net "PCIE_COMP_B_RST_5")
			(options
				(clearance outline)
				(anchor circle)
			)
			(primitives
				(gr_poly
					(pts
						(arc
							(start -0.1778 -0.2794)
							(mid -0.249642 -0.249642)
							(end -0.2794 -0.1778)
						)
						(arc
							(start -0.2794 0.1778)
							(mid -0.249642 0.249642)
							(end -0.1778 0.2794)
						)
						(arc
							(start 0.1778 0.2794)
							(mid 0.249642 0.249642)
							(end 0.2794 0.1778)
						)
						(arc
							(start 0.2794 -0.1778)
							(mid 0.249642 -0.249642)
							(end 0.1778 -0.2794)
						)
					)
					(width 0)
					(fill yes)
				)
			)
		)
		(pad "2" smd custom
			(at 0 0.4445 270)
			(size 0.1397 0.1397)
			(layers "F.Cu" "F.Mask" "F.Paste")
			(net "GND")
			(options
				(clearance outline)
				(anchor circle)
			)
			(primitives
				(gr_poly
					(pts
						(arc
							(start -0.1778 -0.2794)
							(mid -0.249642 -0.249642)
							(end -0.2794 -0.1778)
						)
						(arc
							(start -0.2794 0.1778)
							(mid -0.249642 0.249642)
							(end -0.1778 0.2794)
						)
						(arc
							(start 0.1778 0.2794)
							(mid 0.249642 0.249642)
							(end 0.2794 0.1778)
						)
						(arc
							(start 0.2794 -0.1778)
							(mid 0.249642 -0.249642)
							(end 0.1778 -0.2794)
						)
					)
					(width 0)
					(fill yes)
				)
			)
		)
	)
	(footprint ""
		(layer "F.Cu")
		(at 330.090526 -22.654514 180)
		(property "Reference" "R1010"
			(at 0 0 180)
			(layer "F.SilkS")
			(hide yes)
			(effects
				(font
					(size 1.27 1.27)
				)
			)
		)
		(property "Value" "0R2J-2-GP"
			(at 0.064008 -3.993896 180)
			(unlocked yes)
			(layer "F.Fab")
			(hide yes)
			(effects
				(font
					(size 1.016 1.016)
					(thickness 0.1524)
				)
			)
		)
		(property "Device Type" "R402H16"
			(at 0.064008 -5.517896 180)
			(unlocked yes)
			(layer "F.Fab")
			(hide yes)
			(effects
				(font
					(size 1.016 1.016)
					(thickness 0.1524)
				)
			)
		)
		(duplicate_pad_numbers_are_jumpers no)
		(fp_line
			(start 0.508 -0.9398)
			(end -0.508 -0.9398)
			(stroke
				(width 0.1524)
				(type default)
			)
			(layer "F.SilkS")
		)
		(fp_line
			(start -0.508 -0.9398)
			(end -0.508 0.9398)
			(stroke
				(width 0.1524)
				(type default)
			)
			(layer "F.SilkS")
		)
		(fp_rect
			(start -0.508 0.9398)
			(end 0.508 -0.9398)
			(stroke
				(width 0)
				(type default)
			)
			(fill no)
			(layer "F.CrtYd")
		)
		(fp_rect
			(start -0.508 0.9398)
			(end 0.508 -0.9398)
			(stroke
				(width 0)
				(type default)
			)
			(fill no)
			(layer "F.Fab")
		)
		(pad "1" smd custom
			(at 0 -0.4445 180)
			(size 0.1397 0.1397)
			(layers "F.Cu" "F.Mask" "F.Paste")
			(net "GND")
			(options
				(clearance outline)
				(anchor circle)
			)
			(primitives
				(gr_poly
					(pts
						(arc
							(start -0.1778 -0.2794)
							(mid -0.249642 -0.249642)
							(end -0.2794 -0.1778)
						)
						(arc
							(start -0.2794 0.1778)
							(mid -0.249642 0.249642)
							(end -0.1778 0.2794)
						)
						(arc
							(start 0.1778 0.2794)
							(mid 0.249642 0.249642)
							(end 0.2794 0.1778)
						)
						(arc
							(start 0.2794 -0.1778)
							(mid 0.249642 -0.249642)
							(end 0.1778 -0.2794)
						)
					)
					(width 0)
					(fill yes)
				)
			)
		)
		(pad "2" smd custom
			(at 0 0.4445 180)
			(size 0.1397 0.1397)
			(layers "F.Cu" "F.Mask" "F.Paste")
			(net "IOM_B_SLOT_ID_1")
			(options
				(clearance outline)
				(anchor circle)
			)
			(primitives
				(gr_poly
					(pts
						(arc
							(start -0.1778 -0.2794)
							(mid -0.249642 -0.249642)
							(end -0.2794 -0.1778)
						)
						(arc
							(start -0.2794 0.1778)
							(mid -0.249642 0.249642)
							(end -0.1778 0.2794)
						)
						(arc
							(start 0.1778 0.2794)
							(mid 0.249642 0.249642)
							(end 0.2794 0.1778)
						)
						(arc
							(start 0.2794 -0.1778)
							(mid 0.249642 -0.249642)
							(end 0.1778 -0.2794)
						)
					)
					(width 0)
					(fill yes)
				)
			)
		)
	)
	(footprint ""
		(layer "F.Cu")
		(at 246.992902 -395.012164 180)
		(property "Reference" "R1170"
			(at 0 0 180)
			(layer "F.SilkS")
			(hide yes)
			(effects
				(font
					(size 1.27 1.27)
				)
			)
		)
		(property "Value" "3K92R2F-GP"
			(at 0.064008 -3.993896 180)
			(unlocked yes)
			(layer "F.Fab")
			(hide yes)
			(effects
				(font
					(size 1.016 1.016)
					(thickness 0.1524)
				)
			)
		)
		(property "Device Type" "R402H16"
			(at 0.064008 -5.517896 180)
			(unlocked yes)
			(layer "F.Fab")
			(hide yes)
			(effects
				(font
					(size 1.016 1.016)
					(thickness 0.1524)
				)
			)
		)
		(duplicate_pad_numbers_are_jumpers no)
		(fp_line
			(start 0.508 -0.9398)
			(end -0.508 -0.9398)
			(stroke
				(width 0.1524)
				(type default)
			)
			(layer "F.SilkS")
		)
		(fp_line
			(start -0.508 -0.9398)
			(end -0.508 0.9398)
			(stroke
				(width 0.1524)
				(type default)
			)
			(layer "F.SilkS")
		)
		(fp_rect
			(start -0.508 0.9398)
			(end 0.508 -0.9398)
			(stroke
				(width 0)
				(type default)
			)
			(fill no)
			(layer "F.CrtYd")
		)
		(fp_rect
			(start -0.508 0.9398)
			(end 0.508 -0.9398)
			(stroke
				(width 0)
				(type default)
			)
			(fill no)
			(layer "F.Fab")
		)
		(pad "1" smd custom
			(at 0 -0.4445 180)
			(size 0.1397 0.1397)
			(layers "F.Cu" "F.Mask" "F.Paste")
			(net "MB3_CM_OV_R")
			(options
				(clearance outline)
				(anchor circle)
			)
			(primitives
				(gr_poly
					(pts
						(arc
							(start -0.1778 -0.2794)
							(mid -0.249642 -0.249642)
							(end -0.2794 -0.1778)
						)
						(arc
							(start -0.2794 0.1778)
							(mid -0.249642 0.249642)
							(end -0.1778 0.2794)
						)
						(arc
							(start 0.1778 0.2794)
							(mid 0.249642 0.249642)
							(end 0.2794 0.1778)
						)
						(arc
							(start 0.2794 -0.1778)
							(mid 0.249642 -0.249642)
							(end 0.1778 -0.2794)
						)
					)
					(width 0)
					(fill yes)
				)
			)
		)
		(pad "2" smd custom
			(at 0 0.4445 180)
			(size 0.1397 0.1397)
			(layers "F.Cu" "F.Mask" "F.Paste")
			(net "AGND_CURRENT_DPB")
			(options
				(clearance outline)
				(anchor circle)
			)
			(primitives
				(gr_poly
					(pts
						(arc
							(start -0.1778 -0.2794)
							(mid -0.249642 -0.249642)
							(end -0.2794 -0.1778)
						)
						(arc
							(start -0.2794 0.1778)
							(mid -0.249642 0.249642)
							(end -0.1778 0.2794)
						)
						(arc
							(start 0.1778 0.2794)
							(mid 0.249642 0.249642)
							(end 0.2794 0.1778)
						)
						(arc
							(start 0.2794 -0.1778)
							(mid 0.249642 -0.249642)
							(end 0.1778 -0.2794)
						)
					)
					(width 0)
					(fill yes)
				)
			)
		)
	)
	(footprint ""
		(layer "F.Cu")
		(at 158.503112 -127.71247 180)
		(property "Reference" "Q280"
			(at 0 0 180)
			(layer "F.SilkS")
			(hide yes)
			(effects
				(font
					(size 1.27 1.27)
				)
			)
		)
		(property "Value" "SSM3K324R-GP"
			(at 0.127 -8.9662 180)
			(unlocked yes)
			(layer "F.Fab")
			(hide yes)
			(effects
				(font
					(size 1.016 1.016)
					(thickness 0.1524)
				)
			)
		)
		(property "Device Type" "SOT23DGS2D4H35"
			(at 0.127 -10.4902 180)
			(unlocked yes)
			(layer "F.Fab")
			(hide yes)
			(effects
				(font
					(size 1.016 1.016)
					(thickness 0.1524)
				)
			)
		)
		(duplicate_pad_numbers_are_jumpers no)
		(fp_line
			(start 1.651 1.778)
			(end 1.651 -1.778)
			(stroke
				(width 0.1524)
				(type default)
			)
			(layer "F.SilkS")
		)
		(fp_line
			(start 1.651 -1.778)
			(end -1.651 -1.778)
			(stroke
				(width 0.1524)
				(type default)
			)
			(layer "F.SilkS")
		)
		(fp_line
			(start -1.651 1.778)
			(end 1.651 1.778)
			(stroke
				(width 0.1524)
				(type default)
			)
			(layer "F.SilkS")
		)
		(fp_line
			(start -1.651 -1.778)
			(end -1.651 1.778)
			(stroke
				(width 0.1524)
				(type default)
			)
			(layer "F.SilkS")
		)
		(fp_poly
			(pts
				(xy -1.778 1.8796) (xy -1.778 -1.8796) (xy 1.778 -1.8796) (xy 1.778 1.8796)
			)
			(stroke
				(width 0)
				(type default)
			)
			(fill no)
			(layer "F.CrtYd")
		)
		(fp_poly
			(pts
				(xy -1.778 1.8796) (xy -1.778 -1.8796) (xy 1.778 -1.8796) (xy 1.778 1.8796)
			)
			(stroke
				(width 0)
				(type default)
			)
			(fill no)
			(layer "F.Fab")
		)
		(pad "D" smd custom
			(at 0 -0.9525 180)
			(size 0.1905 0.1905)
			(layers "F.Cu" "F.Mask" "F.Paste")
			(net "DRV_ACT_17_N")
			(options
				(clearance outline)
				(anchor circle)
			)
			(primitives
				(gr_poly
					(pts
						(arc
							(start -0.1778 0.5715)
							(mid -0.321484 0.511984)
							(end -0.381 0.3683)
						)
						(arc
							(start -0.381 -0.3683)
							(mid -0.321484 -0.511984)
							(end -0.1778 -0.5715)
						)
						(arc
							(start 0.1778 -0.5715)
							(mid 0.321484 -0.511984)
							(end 0.381 -0.3683)
						)
						(arc
							(start 0.381 0.3683)
							(mid 0.321484 0.511984)
							(end 0.1778 0.5715)
						)
					)
					(width 0)
					(fill yes)
				)
			)
		)
		(pad "G" smd custom
			(at -0.98425 0.9525 180)
			(size 0.1905 0.1905)
			(layers "F.Cu" "F.Mask" "F.Paste")
			(net "DRIVE_A_17_ACT")
			(options
				(clearance outline)
				(anchor circle)
			)
			(primitives
				(gr_poly
					(pts
						(arc
							(start -0.1778 0.5715)
							(mid -0.321484 0.511984)
							(end -0.381 0.3683)
						)
						(arc
							(start -0.381 -0.3683)
							(mid -0.321484 -0.511984)
							(end -0.1778 -0.5715)
						)
						(arc
							(start 0.1778 -0.5715)
							(mid 0.321484 -0.511984)
							(end 0.381 -0.3683)
						)
						(arc
							(start 0.381 0.3683)
							(mid 0.321484 0.511984)
							(end 0.1778 0.5715)
						)
					)
					(width 0)
					(fill yes)
				)
			)
		)
		(pad "S" smd custom
			(at 0.98425 0.9525 180)
			(size 0.1905 0.1905)
			(layers "F.Cu" "F.Mask" "F.Paste")
			(net "GND")
			(options
				(clearance outline)
				(anchor circle)
			)
			(primitives
				(gr_poly
					(pts
						(arc
							(start -0.1778 0.5715)
							(mid -0.321484 0.511984)
							(end -0.381 0.3683)
						)
						(arc
							(start -0.381 -0.3683)
							(mid -0.321484 -0.511984)
							(end -0.1778 -0.5715)
						)
						(arc
							(start 0.1778 -0.5715)
							(mid 0.321484 -0.511984)
							(end 0.381 -0.3683)
						)
						(arc
							(start 0.381 0.3683)
							(mid 0.321484 0.511984)
							(end 0.1778 0.5715)
						)
					)
					(width 0)
					(fill yes)
				)
			)
		)
	)
	(footprint ""
		(layer "F.Cu")
		(at 140.915898 -294.683942 -90)
		(property "Reference" "C97"
			(at 0 0 270)
			(layer "F.SilkS")
			(hide yes)
			(effects
				(font
					(size 1.27 1.27)
				)
			)
		)
		(property "Value" "SC4D7U25V5KX-1-GP"
			(at -0.0762 -6.1214 270)
			(unlocked yes)
			(layer "F.Fab")
			(hide yes)
			(effects
				(font
					(size 1.016 1.016)
					(thickness 0.1524)
				)
			)
		)
		(property "Device Type" "C805H58"
			(at -0.0762 -8.1534 270)
			(unlocked yes)
			(layer "F.Fab")
			(hide yes)
			(effects
				(font
					(size 1.016 1.016)
					(thickness 0.1524)
				)
			)
		)
		(duplicate_pad_numbers_are_jumpers no)
		(fp_line
			(start 0.635 0)
			(end -0.635 0)
			(stroke
				(width 0.508)
				(type default)
			)
			(layer "F.SilkS")
		)
		(fp_rect
			(start -0.9652 1.778)
			(end 0.9652 -1.778)
			(stroke
				(width 0)
				(type default)
			)
			(fill no)
			(layer "F.CrtYd")
		)
		(fp_poly
			(pts
				(xy -0.9652 -1.778) (xy 0.9652 -1.778) (xy 0.9652 1.778) (xy -0.9652 1.778)
			)
			(stroke
				(width 0)
				(type default)
			)
			(fill no)
			(layer "F.Fab")
		)
		(pad "1" smd rect
			(at 0 -0.9652 270)
			(size 1.397 1.143)
			(layers "F.Cu" "F.Mask" "F.Paste")
			(net "P12V_HDD4")
		)
		(pad "2" smd rect
			(at 0 0.9652 270)
			(size 1.397 1.143)
			(layers "F.Cu" "F.Mask" "F.Paste")
			(net "GND")
		)
	)
	(footprint ""
		(layer "F.Cu")
		(at 222.593916 -113.147348 -90)
		(property "Reference" "R159"
			(at 0 0 270)
			(layer "F.SilkS")
			(hide yes)
			(effects
				(font
					(size 1.27 1.27)
				)
			)
		)
		(property "Value" "0R2J-2-GP"
			(at 0.064008 -3.993896 270)
			(unlocked yes)
			(layer "F.Fab")
			(hide yes)
			(effects
				(font
					(size 1.016 1.016)
					(thickness 0.1524)
				)
			)
		)
		(property "Device Type" "R402H16"
			(at 0.064008 -5.517896 270)
			(unlocked yes)
			(layer "F.Fab")
			(hide yes)
			(effects
				(font
					(size 1.016 1.016)
					(thickness 0.1524)
				)
			)
		)
		(duplicate_pad_numbers_are_jumpers no)
		(fp_line
			(start -0.508 -0.9398)
			(end -0.508 0.9398)
			(stroke
				(width 0.1524)
				(type default)
			)
			(layer "F.SilkS")
		)
		(fp_line
			(start 0.508 -0.9398)
			(end -0.508 -0.9398)
			(stroke
				(width 0.1524)
				(type default)
			)
			(layer "F.SilkS")
		)
		(fp_rect
			(start -0.508 0.9398)
			(end 0.508 -0.9398)
			(stroke
				(width 0)
				(type default)
			)
			(fill no)
			(layer "F.CrtYd")
		)
		(fp_rect
			(start -0.508 0.9398)
			(end 0.508 -0.9398)
			(stroke
				(width 0)
				(type default)
			)
			(fill no)
			(layer "F.Fab")
		)
		(pad "1" smd custom
			(at 0 -0.4445 270)
			(size 0.1397 0.1397)
			(layers "F.Cu" "F.Mask" "F.Paste")
			(net "SLOT3_SVR_ID0_GPIO0")
			(options
				(clearance outline)
				(anchor circle)
			)
			(primitives
				(gr_poly
					(pts
						(arc
							(start -0.1778 -0.2794)
							(mid -0.249642 -0.249642)
							(end -0.2794 -0.1778)
						)
						(arc
							(start -0.2794 0.1778)
							(mid -0.249642 0.249642)
							(end -0.1778 0.2794)
						)
						(arc
							(start 0.1778 0.2794)
							(mid 0.249642 0.249642)
							(end 0.2794 0.1778)
						)
						(arc
							(start 0.2794 -0.1778)
							(mid 0.249642 -0.249642)
							(end 0.1778 -0.2794)
						)
					)
					(width 0)
					(fill yes)
				)
			)
		)
		(pad "2" smd custom
			(at 0 0.4445 270)
			(size 0.1397 0.1397)
			(layers "F.Cu" "F.Mask" "F.Paste")
			(net "COMP_A_BMC_A_SPARE_0")
			(options
				(clearance outline)
				(anchor circle)
			)
			(primitives
				(gr_poly
					(pts
						(arc
							(start -0.1778 -0.2794)
							(mid -0.249642 -0.249642)
							(end -0.2794 -0.1778)
						)
						(arc
							(start -0.2794 0.1778)
							(mid -0.249642 0.249642)
							(end -0.1778 0.2794)
						)
						(arc
							(start 0.1778 0.2794)
							(mid 0.249642 0.249642)
							(end 0.2794 0.1778)
						)
						(arc
							(start 0.2794 -0.1778)
							(mid 0.249642 -0.249642)
							(end 0.1778 -0.2794)
						)
					)
					(width 0)
					(fill yes)
				)
			)
		)
	)
)
